(kicad_pcb
	(version 20260206)
	(generator "pcbnew")
	(generator_version "10.0")
	(general
		(thickness 1.6)
		(legacy_teardrops no)
	)
	(paper "A4")
	(title_block
		(title "Bryce Canyon_R.DPB_16317-1_OCP.brd")
		(comment 1 "Bryce Canyon / footprints 1346-1353 of 2099")
	)
	(layers
		(0 "F.Cu" signal "TOP")
		(4 "In1.Cu" signal "L2GND")
		(6 "In2.Cu" signal "L3")
		(8 "In3.Cu" signal "L4VCC")
		(10 "In4.Cu" signal "L5VCC")
		(12 "In5.Cu" signal "L6")
		(14 "In6.Cu" signal "L7GND")
		(2 "B.Cu" signal "BOTTOM")
		(9 "F.Adhes" user "F.Adhesive")
		(11 "B.Adhes" user "B.Adhesive")
		(13 "F.Paste" user "Package Geometry/Pastemask Top")
		(15 "B.Paste" user "Package Geometry/Pastemask Bottom")
		(5 "F.SilkS" user "Ref Des/Silkscreen Top")
		(7 "B.SilkS" user "Ref Des/Silkscreen Bottom")
		(1 "F.Mask" user "Board Geometry/Soldermask Top")
		(3 "B.Mask" user "Board Geometry/Soldermask Bottom")
		(17 "Dwgs.User" user "User.Drawings")
		(19 "Cmts.User" user "User.Comments")
		(21 "Eco1.User" user "User.Eco1")
		(23 "Eco2.User" user "User.Eco2")
		(25 "Edge.Cuts" user "Board Geometry/Outline")
		(27 "Margin" user)
		(31 "F.CrtYd" user "Package Geometry/Place Bound Top")
		(29 "B.CrtYd" user "Package Geometry/Place Bound Bottom")
		(35 "F.Fab" user "Ref Des/Assembly Top")
		(33 "B.Fab" user "Ref Des/Assembly Bottom")
	)
	(footprint ""
		(layer "F.Cu")
		(at 237.49 -215.265)
		(property "Reference" "R87"
			(at 0 0 0)
			(layer "F.SilkS")
			(hide yes)
			(effects
				(font
					(size 1.27 1.27)
				)
			)
		)
		(property "Value" "0R2J-2-GP"
			(at 0.064008 -3.993896 0)
			(unlocked yes)
			(layer "F.Fab")
			(hide yes)
			(effects
				(font
					(size 1.016 1.016)
					(thickness 0.1524)
				)
			)
		)
		(property "Device Type" "R402H16"
			(at 0.064008 -5.517896 0)
			(unlocked yes)
			(layer "F.Fab")
			(hide yes)
			(effects
				(font
					(size 1.016 1.016)
					(thickness 0.1524)
				)
			)
		)
		(duplicate_pad_numbers_are_jumpers no)
		(fp_line
			(start -0.508 -0.9398)
			(end -0.508 0.9398)
			(stroke
				(width 0.1524)
				(type default)
			)
			(layer "F.SilkS")
		)
		(fp_line
			(start 0.508 -0.9398)
			(end -0.508 -0.9398)
			(stroke
				(width 0.1524)
				(type default)
			)
			(layer "F.SilkS")
		)
		(fp_rect
			(start -0.508 0.9398)
			(end 0.508 -0.9398)
			(stroke
				(width 0)
				(type default)
			)
			(fill no)
			(layer "F.CrtYd")
		)
		(fp_rect
			(start -0.508 0.9398)
			(end 0.508 -0.9398)
			(stroke
				(width 0)
				(type default)
			)
			(fill no)
			(layer "F.Fab")
		)
		(pad "1" smd custom
			(at 0 -0.4445)
			(size 0.1397 0.1397)
			(layers "F.Cu" "F.Mask" "F.Paste")
			(net "IO_EXP3_SCL")
			(options
				(clearance outline)
				(anchor circle)
			)
			(primitives
				(gr_poly
					(pts
						(arc
							(start -0.1778 -0.2794)
							(mid -0.249642 -0.249642)
							(end -0.2794 -0.1778)
						)
						(arc
							(start -0.2794 0.1778)
							(mid -0.249642 0.249642)
							(end -0.1778 0.2794)
						)
						(arc
							(start 0.1778 0.2794)
							(mid 0.249642 0.249642)
							(end 0.2794 0.1778)
						)
						(arc
							(start 0.2794 -0.1778)
							(mid 0.249642 -0.249642)
							(end 0.1778 -0.2794)
						)
					)
					(width 0)
					(fill yes)
				)
			)
		)
		(pad "2" smd custom
			(at 0 0.4445)
			(size 0.1397 0.1397)
			(layers "F.Cu" "F.Mask" "F.Paste")
			(net "I2C_DRIVE_B_PWR_SCL")
			(options
				(clearance outline)
				(anchor circle)
			)
			(primitives
				(gr_poly
					(pts
						(arc
							(start -0.1778 -0.2794)
							(mid -0.249642 -0.249642)
							(end -0.2794 -0.1778)
						)
						(arc
							(start -0.2794 0.1778)
							(mid -0.249642 0.249642)
							(end -0.1778 0.2794)
						)
						(arc
							(start 0.1778 0.2794)
							(mid 0.249642 0.249642)
							(end 0.2794 0.1778)
						)
						(arc
							(start 0.2794 -0.1778)
							(mid 0.249642 -0.249642)
							(end 0.1778 -0.2794)
						)
					)
					(width 0)
					(fill yes)
				)
			)
		)
	)
	(footprint ""
		(layer "F.Cu")
		(at 23.876 -272.288)
		(property "Reference" "C503"
			(at 0 0 0)
			(layer "F.SilkS")
			(hide yes)
			(effects
				(font
					(size 1.27 1.27)
				)
			)
		)
		(property "Value" "SC4D7U25V5KX-1-GP"
			(at -0.0762 -6.1214 0)
			(unlocked yes)
			(layer "F.Fab")
			(hide yes)
			(effects
				(font
					(size 1.016 1.016)
					(thickness 0.1524)
				)
			)
		)
		(property "Device Type" "C805H58"
			(at -0.0762 -8.1534 0)
			(unlocked yes)
			(layer "F.Fab")
			(hide yes)
			(effects
				(font
					(size 1.016 1.016)
					(thickness 0.1524)
				)
			)
		)
		(duplicate_pad_numbers_are_jumpers no)
		(fp_line
			(start 0.635 0)
			(end -0.635 0)
			(stroke
				(width 0.508)
				(type default)
			)
			(layer "F.SilkS")
		)
		(fp_rect
			(start -0.9652 1.778)
			(end 0.9652 -1.778)
			(stroke
				(width 0)
				(type default)
			)
			(fill no)
			(layer "F.CrtYd")
		)
		(fp_poly
			(pts
				(xy -0.9652 -1.778) (xy 0.9652 -1.778) (xy 0.9652 1.778) (xy -0.9652 1.778)
			)
			(stroke
				(width 0)
				(type default)
			)
			(fill no)
			(layer "F.Fab")
		)
		(pad "1" smd rect
			(at 0 -0.9652)
			(size 1.397 1.143)
			(layers "F.Cu" "F.Mask" "F.Paste")
			(net "P12V_HDD0")
		)
		(pad "2" smd rect
			(at 0 0.9652)
			(size 1.397 1.143)
			(layers "F.Cu" "F.Mask" "F.Paste")
			(net "GND")
		)
	)
	(footprint ""
		(layer "F.Cu")
		(at 16.764 -138.049 90)
		(property "Reference" "R355"
			(at 0 0 90)
			(layer "F.SilkS")
			(hide yes)
			(effects
				(font
					(size 1.27 1.27)
				)
			)
		)
		(property "Value" "4K7R2J-2-GP"
			(at 0.064008 -3.993896 90)
			(unlocked yes)
			(layer "F.Fab")
			(hide yes)
			(effects
				(font
					(size 1.016 1.016)
					(thickness 0.1524)
				)
			)
		)
		(property "Device Type" "R402H16"
			(at 0.064008 -5.517896 90)
			(unlocked yes)
			(layer "F.Fab")
			(hide yes)
			(effects
				(font
					(size 1.016 1.016)
					(thickness 0.1524)
				)
			)
		)
		(duplicate_pad_numbers_are_jumpers no)
		(fp_line
			(start 0.508 -0.9398)
			(end -0.508 -0.9398)
			(stroke
				(width 0.1524)
				(type default)
			)
			(layer "F.SilkS")
		)
		(fp_line
			(start -0.508 -0.9398)
			(end -0.508 0.9398)
			(stroke
				(width 0.1524)
				(type default)
			)
			(layer "F.SilkS")
		)
		(fp_rect
			(start -0.508 0.9398)
			(end 0.508 -0.9398)
			(stroke
				(width 0)
				(type default)
			)
			(fill no)
			(layer "F.CrtYd")
		)
		(fp_rect
			(start -0.508 0.9398)
			(end 0.508 -0.9398)
			(stroke
				(width 0)
				(type default)
			)
			(fill no)
			(layer "F.Fab")
		)
		(pad "1" smd custom
			(at 0 -0.4445 90)
			(size 0.1397 0.1397)
			(layers "F.Cu" "F.Mask" "F.Paste")
			(net "P12V_B")
			(options
				(clearance outline)
				(anchor circle)
			)
			(primitives
				(gr_poly
					(pts
						(arc
							(start -0.1778 -0.2794)
							(mid -0.249642 -0.249642)
							(end -0.2794 -0.1778)
						)
						(arc
							(start -0.2794 0.1778)
							(mid -0.249642 0.249642)
							(end -0.1778 0.2794)
						)
						(arc
							(start 0.1778 0.2794)
							(mid 0.249642 0.249642)
							(end 0.2794 0.1778)
						)
						(arc
							(start 0.2794 -0.1778)
							(mid 0.249642 -0.249642)
							(end 0.1778 -0.2794)
						)
					)
					(width 0)
					(fill yes)
				)
			)
		)
		(pad "2" smd custom
			(at 0 0.4445 90)
			(size 0.1397 0.1397)
			(layers "F.Cu" "F.Mask" "F.Paste")
			(net "SW_HDD_P12")
			(options
				(clearance outline)
				(anchor circle)
			)
			(primitives
				(gr_poly
					(pts
						(arc
							(start -0.1778 -0.2794)
							(mid -0.249642 -0.249642)
							(end -0.2794 -0.1778)
						)
						(arc
							(start -0.2794 0.1778)
							(mid -0.249642 0.249642)
							(end -0.1778 0.2794)
						)
						(arc
							(start 0.1778 0.2794)
							(mid 0.249642 0.249642)
							(end 0.2794 0.1778)
						)
						(arc
							(start 0.2794 -0.1778)
							(mid 0.249642 -0.249642)
							(end 0.1778 -0.2794)
						)
					)
					(width 0)
					(fill yes)
				)
			)
		)
	)
	(footprint ""
		(layer "F.Cu")
		(at 52.197 -141.224 180)
		(property "Reference" "Q51"
			(at 0 0 180)
			(layer "F.SilkS")
			(hide yes)
			(effects
				(font
					(size 1.27 1.27)
				)
			)
		)
		(property "Value" "AO4406AL-GP"
			(at -3.707384 -1.5367 180)
			(unlocked yes)
			(layer "F.Fab")
			(hide yes)
			(effects
				(font
					(size 1.016 1.016)
					(thickness 0.1524)
				)
			)
		)
		(property "Device Type" "SOIC8H69"
			(at -3.707384 -3.0607 180)
			(unlocked yes)
			(layer "F.Fab")
			(hide yes)
			(effects
				(font
					(size 1.016 1.016)
					(thickness 0.1524)
				)
			)
		)
		(duplicate_pad_numbers_are_jumpers no)
		(fp_line
			(start 2.1336 1.4224)
			(end 2.1336 -1.4224)
			(stroke
				(width 0.1524)
				(type default)
			)
			(layer "F.SilkS")
		)
		(fp_line
			(start 2.1336 -1.4224)
			(end -2.7432 -1.4224)
			(stroke
				(width 0.1524)
				(type default)
			)
			(layer "F.SilkS")
		)
		(fp_line
			(start -2.1844 -0.0508)
			(end -2.7178 0.508)
			(stroke
				(width 0.1524)
				(type default)
			)
			(layer "F.SilkS")
		)
		(fp_line
			(start -2.6289 3.4417)
			(end -2.6289 1.4732)
			(stroke
				(width 0.381)
				(type default)
			)
			(layer "F.SilkS")
		)
		(fp_line
			(start -2.7178 -0.508)
			(end -2.1844 -0.0508)
			(stroke
				(width 0.1524)
				(type default)
			)
			(layer "F.SilkS")
		)
		(fp_line
			(start -2.7432 1.4224)
			(end 2.1336 1.4224)
			(stroke
				(width 0.1524)
				(type default)
			)
			(layer "F.SilkS")
		)
		(fp_line
			(start -2.7432 1.4224)
			(end -2.6416 1.4224)
			(stroke
				(width 0.1524)
				(type default)
			)
			(layer "F.SilkS")
		)
		(fp_line
			(start -2.7432 -1.4224)
			(end -2.7432 1.4224)
			(stroke
				(width 0.1524)
				(type default)
			)
			(layer "F.SilkS")
		)
		(fp_poly
			(pts
				(xy -2.2098 -1.4224) (xy -2.2098 1.4224) (xy 2.2098 1.4224) (xy 2.2098 -1.4224)
			)
			(stroke
				(width 0)
				(type default)
			)
			(fill yes)
			(layer "F.SilkS")
		)
		(fp_rect
			(start -2.450084 2.999994)
			(end 2.450084 -2.999994)
			(stroke
				(width 0)
				(type default)
			)
			(fill no)
			(layer "F.CrtYd")
		)
		(fp_poly
			(pts
				(xy -2.8194 3.6322) (xy -2.8194 -3.6322) (xy 2.8194 -3.6322) (xy 2.8194 1.18364) (xy 2.450084 1.18364)
				(xy 2.450084 -2.999994) (xy -2.450084 -2.999994) (xy -2.450084 2.999994) (xy 2.450084 2.999994)
				(xy 2.450084 1.18618) (xy 2.8194 1.18618) (xy 2.8194 3.6322)
			)
			(stroke
				(width 0)
				(type default)
			)
			(fill no)
			(layer "F.CrtYd")
		)
		(fp_rect
			(start -2.8194 3.6322)
			(end 2.8194 -3.6322)
			(stroke
				(width 0)
				(type default)
			)
			(fill no)
			(layer "F.Fab")
		)
		(pad "1" smd rect
			(at -1.905 2.54 180)
			(size 0.635 1.651)
			(layers "F.Cu" "F.Mask" "F.Paste")
			(net "P5V_HDD13")
		)
		(pad "2" smd rect
			(at -0.635 2.54 180)
			(size 0.635 1.651)
			(layers "F.Cu" "F.Mask" "F.Paste")
			(net "P5V_HDD13")
		)
		(pad "3" smd rect
			(at 0.635 2.54 180)
			(size 0.635 1.651)
			(layers "F.Cu" "F.Mask" "F.Paste")
			(net "P5V_HDD13")
		)
		(pad "4" smd rect
			(at 1.905 2.54 180)
			(size 0.635 1.651)
			(layers "F.Cu" "F.Mask" "F.Paste")
			(net "SW_HDD_P13")
		)
		(pad "5" smd rect
			(at 1.905 -2.54 180)
			(size 0.635 1.651)
			(layers "F.Cu" "F.Mask" "F.Paste")
			(net "P5V_B_1")
		)
		(pad "6" smd rect
			(at 0.635 -2.54 180)
			(size 0.635 1.651)
			(layers "F.Cu" "F.Mask" "F.Paste")
			(net "P5V_B_1")
		)
		(pad "7" smd rect
			(at -0.635 -2.54 180)
			(size 0.635 1.651)
			(layers "F.Cu" "F.Mask" "F.Paste")
			(net "P5V_B_1")
		)
		(pad "8" smd rect
			(at -1.905 -2.54 180)
			(size 0.635 1.651)
			(layers "F.Cu" "F.Mask" "F.Paste")
			(net "P5V_B_1")
		)
	)
	(footprint ""
		(layer "F.Cu")
		(at 55.499 -272.288)
		(property "Reference" "C49"
			(at 0 0 0)
			(layer "F.SilkS")
			(hide yes)
			(effects
				(font
					(size 1.27 1.27)
				)
			)
		)
		(property "Value" "SC4D7U25V5KX-1-GP"
			(at -0.0762 -6.1214 0)
			(unlocked yes)
			(layer "F.Fab")
			(hide yes)
			(effects
				(font
					(size 1.016 1.016)
					(thickness 0.1524)
				)
			)
		)
		(property "Device Type" "C805H58"
			(at -0.0762 -8.1534 0)
			(unlocked yes)
			(layer "F.Fab")
			(hide yes)
			(effects
				(font
					(size 1.016 1.016)
					(thickness 0.1524)
				)
			)
		)
		(duplicate_pad_numbers_are_jumpers no)
		(fp_line
			(start 0.635 0)
			(end -0.635 0)
			(stroke
				(width 0.508)
				(type default)
			)
			(layer "F.SilkS")
		)
		(fp_rect
			(start -0.9652 1.778)
			(end 0.9652 -1.778)
			(stroke
				(width 0)
				(type default)
			)
			(fill no)
			(layer "F.CrtYd")
		)
		(fp_poly
			(pts
				(xy -0.9652 -1.778) (xy 0.9652 -1.778) (xy 0.9652 1.778) (xy -0.9652 1.778)
			)
			(stroke
				(width 0)
				(type default)
			)
			(fill no)
			(layer "F.Fab")
		)
		(pad "1" smd rect
			(at 0 -0.9652)
			(size 1.397 1.143)
			(layers "F.Cu" "F.Mask" "F.Paste")
			(net "P12V_HDD1")
		)
		(pad "2" smd rect
			(at 0 0.9652)
			(size 1.397 1.143)
			(layers "F.Cu" "F.Mask" "F.Paste")
			(net "GND")
		)
	)
	(footprint ""
		(layer "F.Cu")
		(at 170.199812 -13.999972)
		(property "Reference" ""
			(at 0 0 0)
			(layer "F.SilkS")
			(hide yes)
			(effects
				(font
					(size 1.27 1.27)
				)
			)
		)
		(property "Value" "*"
			(at -6.3373 -0.4572 0)
			(unlocked yes)
			(layer "F.Fab")
			(hide yes)
			(effects
				(font
					(size 1.016 1.016)
					(thickness 0.1524)
				)
			)
		)
		(duplicate_pad_numbers_are_jumpers no)
		(fp_poly
			(pts
				(arc
					(start 5.0673 0)
					(mid -5.0673 0)
					(end 5.0673 0)
				)
			)
			(stroke
				(width 0)
				(type default)
			)
			(fill no)
			(layer "B.CrtYd")
		)
		(fp_poly
			(pts
				(arc
					(start 5.0673 0)
					(mid -5.0673 0)
					(end 5.0673 0)
				)
			)
			(stroke
				(width 0)
				(type default)
			)
			(fill no)
			(layer "F.CrtYd")
		)
		(fp_poly
			(pts
				(arc
					(start 5.0673 0)
					(mid -5.0673 0)
					(end 5.0673 0)
				)
			)
			(stroke
				(width 0)
				(type default)
			)
			(fill no)
			(layer "B.Fab")
		)
		(fp_poly
			(pts
				(arc
					(start 5.0673 0)
					(mid -5.0673 0)
					(end 5.0673 0)
				)
			)
			(stroke
				(width 0)
				(type default)
			)
			(fill no)
			(layer "F.Fab")
		)
		(pad "1" thru_hole circle
			(at 0 0)
			(size 9.525 9.525)
			(drill 3.556)
			(layers "*.Cu" "*.Mask")
			(remove_unused_layers no)
			(net "Net_35")
			(clearance -2.4765)
			(thermal_gap 0.3048)
			(padstack
				(mode front_inner_back)
				(layer "Inner"
					(shape circle)
					(size 3.9624 3.9624)
					(clearance 0.3048)
				)
				(layer "B.Cu"
					(shape circle)
					(size 9.525 9.525)
					(clearance -2.4765)
				)
			)
		)
		(zone
			(layers "F.Cu" "B.Cu" "In1.Cu" "In2.Cu" "In3.Cu" "In4.Cu" "In5.Cu" "In6.Cu")
			(hatch none 0.5)
			(connect_pads
				(clearance 0)
			)
			(min_thickness 0.25)
			(keepout
				(tracks not_allowed)
				(vias allowed)
				(pads allowed)
				(copperpour not_allowed)
				(footprints allowed)
			)
			(placement
				(enabled no)
				(sheetname "")
			)
			(fill
				(thermal_gap 0.5)
				(thermal_bridge_width 0.5)
				(island_removal_mode 0)
			)
			(polygon
				(pts
					(arc
						(start 174.962312 -13.999972)
						(mid 165.437312 -13.999972)
						(end 174.962312 -13.999972)
					)
				)
			)
		)
	)
	(footprint ""
		(layer "F.Cu")
		(at 255.3843 -214.31504)
		(property "Reference" "R117"
			(at 0 0 0)
			(layer "F.SilkS")
			(hide yes)
			(effects
				(font
					(size 1.27 1.27)
				)
			)
		)
		(property "Value" "0R2J-2-GP"
			(at 0.064008 -3.993896 0)
			(unlocked yes)
			(layer "F.Fab")
			(hide yes)
			(effects
				(font
					(size 1.016 1.016)
					(thickness 0.1524)
				)
			)
		)
		(property "Device Type" "R402H16"
			(at 0.064008 -5.517896 0)
			(unlocked yes)
			(layer "F.Fab")
			(hide yes)
			(effects
				(font
					(size 1.016 1.016)
					(thickness 0.1524)
				)
			)
		)
		(duplicate_pad_numbers_are_jumpers no)
		(fp_line
			(start -0.508 -0.9398)
			(end -0.508 0.9398)
			(stroke
				(width 0.1524)
				(type default)
			)
			(layer "F.SilkS")
		)
		(fp_line
			(start 0.508 -0.9398)
			(end -0.508 -0.9398)
			(stroke
				(width 0.1524)
				(type default)
			)
			(layer "F.SilkS")
		)
		(fp_rect
			(start -0.508 0.9398)
			(end 0.508 -0.9398)
			(stroke
				(width 0)
				(type default)
			)
			(fill no)
			(layer "F.CrtYd")
		)
		(fp_rect
			(start -0.508 0.9398)
			(end 0.508 -0.9398)
			(stroke
				(width 0)
				(type default)
			)
			(fill no)
			(layer "F.Fab")
		)
		(pad "1" smd custom
			(at 0 -0.4445)
			(size 0.1397 0.1397)
			(layers "F.Cu" "F.Mask" "F.Paste")
			(net "VOL_SEN_SCL")
			(options
				(clearance outline)
				(anchor circle)
			)
			(primitives
				(gr_poly
					(pts
						(arc
							(start -0.1778 -0.2794)
							(mid -0.249642 -0.249642)
							(end -0.2794 -0.1778)
						)
						(arc
							(start -0.2794 0.1778)
							(mid -0.249642 0.249642)
							(end -0.1778 0.2794)
						)
						(arc
							(start 0.1778 0.2794)
							(mid 0.249642 0.249642)
							(end 0.2794 0.1778)
						)
						(arc
							(start 0.2794 -0.1778)
							(mid 0.249642 -0.249642)
							(end 0.1778 -0.2794)
						)
					)
					(width 0)
					(fill yes)
				)
			)
		)
		(pad "2" smd custom
			(at 0 0.4445)
			(size 0.1397 0.1397)
			(layers "F.Cu" "F.Mask" "F.Paste")
			(net "I2C_DPB_B_SCL_BUF")
			(options
				(clearance outline)
				(anchor circle)
			)
			(primitives
				(gr_poly
					(pts
						(arc
							(start -0.1778 -0.2794)
							(mid -0.249642 -0.249642)
							(end -0.2794 -0.1778)
						)
						(arc
							(start -0.2794 0.1778)
							(mid -0.249642 0.249642)
							(end -0.1778 0.2794)
						)
						(arc
							(start 0.1778 0.2794)
							(mid 0.249642 0.249642)
							(end 0.2794 0.1778)
						)
						(arc
							(start 0.2794 -0.1778)
							(mid 0.249642 -0.249642)
							(end 0.1778 -0.2794)
						)
					)
					(width 0)
					(fill yes)
				)
			)
		)
	)
	(footprint ""
		(layer "F.Cu")
		(at 64.0588 -133.75005 -90)
		(property "Reference" "VIA28"
			(at 0 0 270)
			(layer "F.SilkS")
			(hide yes)
			(effects
				(font
					(size 1.27 1.27)
				)
			)
		)
		(property "Value" "100OHM-8L-2D36MM-L16-GP"
			(at -3.4036 -0.4572 270)
			(unlocked yes)
			(layer "F.Fab")
			(hide yes)
			(effects
				(font
					(size 1.016 1.016)
					(thickness 0.1524)
				)
			)
		)
		(property "Device Type" "VIA-PCIE-4P-427097"
			(at -3.4036 -1.9812 270)
			(unlocked yes)
			(layer "F.Fab")
			(hide yes)
			(effects
				(font
					(size 1.016 1.016)
					(thickness 0.1524)
				)
			)
		)
		(duplicate_pad_numbers_are_jumpers no)
		(fp_rect
			(start -2.1336 0.4826)
			(end 2.1336 -0.4826)
			(stroke
				(width 0)
				(type default)
			)
			(fill no)
			(layer "F.CrtYd")
		)
		(fp_rect
			(start -2.1336 0.4826)
			(end 2.1336 -0.4826)
			(stroke
				(width 0)
				(type default)
			)
			(fill no)
			(layer "F.Fab")
		)
		(pad "1" thru_hole circle
			(at -1.651 0 270)
			(size 0.508 0.508)
			(drill 0.254)
			(layers "*.Cu" "*.Mask")
			(remove_unused_layers no)
			(net "GND")
			(clearance 0.2286)
			(thermal_gap 0.2286)
		)
		(pad "2" thru_hole circle
			(at -0.635 0 270)
			(size 0.508 0.508)
			(drill 0.254)
			(layers "*.Cu" "*.Mask")
			(remove_unused_layers no)
			(net "PHY_DRV_B_TO_SCC_B_13_DP")
			(clearance 0.2286)
			(thermal_gap 0.2286)
		)
		(pad "3" thru_hole circle
			(at 0.635 0 270)
			(size 0.508 0.508)
			(drill 0.254)
			(layers "*.Cu" "*.Mask")
			(remove_unused_layers no)
			(net "PHY_DRV_B_TO_SCC_B_13_DN")
			(clearance 0.2286)
			(thermal_gap 0.2286)
		)
		(pad "4" thru_hole circle
			(at 1.651 0 270)
			(size 0.508 0.508)
			(drill 0.254)
			(layers "*.Cu" "*.Mask")
			(remove_unused_layers no)
			(net "GND")
			(clearance 0.2286)
			(thermal_gap 0.2286)
		)
	)
)
